(kicad_pcb
	(version 20260206)
	(generator "pcbnew")
	(generator_version "10.0")
	(general
		(thickness 1.6)
		(legacy_teardrops no)
	)
	(paper "A4")
	(title_block
		(title "04192023_DAF0TMB3IC0_F0TG_MB_C_brd_V02_OCP.brd")
		(comment 1 "Grand Teton / footprints 5912-5920 of 8354")
	)
	(layers
		(0 "F.Cu" signal "TOP")
		(4 "In1.Cu" signal "GND")
		(6 "In2.Cu" signal "IN1")
		(8 "In3.Cu" signal "GND1")
		(10 "In4.Cu" signal "IN2")
		(12 "In5.Cu" signal "GND2")
		(14 "In6.Cu" signal "IN3")
		(16 "In7.Cu" signal "GND3")
		(18 "In8.Cu" signal "VCC")
		(20 "In9.Cu" signal "VCC1")
		(22 "In10.Cu" signal "GND4")
		(24 "In11.Cu" signal "IN4")
		(26 "In12.Cu" signal "GND5")
		(28 "In13.Cu" signal "IN5")
		(30 "In14.Cu" signal "GND6")
		(32 "In15.Cu" signal "IN6")
		(34 "In16.Cu" signal "GND7")
		(2 "B.Cu" signal "BOTTOM")
		(9 "F.Adhes" user "F.Adhesive")
		(11 "B.Adhes" user "B.Adhesive")
		(13 "F.Paste" user "Package Geometry/Pastemask Top")
		(15 "B.Paste" user "Package Geometry/Pastemask Bottom")
		(5 "F.SilkS" user "Ref Des/Silkscreen Top")
		(7 "B.SilkS" user "Ref Des/Silkscreen Bottom")
		(1 "F.Mask" user "Board Geometry/Soldermask Top")
		(3 "B.Mask" user "Board Geometry/Soldermask Bottom")
		(17 "Dwgs.User" user "User.Drawings")
		(19 "Cmts.User" user "User.Comments")
		(21 "Eco1.User" user "User.Eco1")
		(23 "Eco2.User" user "User.Eco2")
		(25 "Edge.Cuts" user "Board Geometry/Outline")
		(27 "Margin" user)
		(31 "F.CrtYd" user "Package Geometry/Place Bound Top")
		(29 "B.CrtYd" user "Package Geometry/Place Bound Bottom")
		(35 "F.Fab" user "Ref Des/Assembly Top")
		(33 "B.Fab" user "Ref Des/Assembly Bottom")
	)
	(footprint ""
		(layer "B.Cu")
		(at 62.996318 -346.788994 90)
		(property "Reference" "PC409_4"
			(at 0 0 90)
			(layer "B.SilkS")
			(hide yes)
			(effects
				(font
					(size 1.27 1.27)
				)
				(justify mirror)
			)
		)
		(property "Value" ""
			(at 0 0 90)
			(layer "B.Fab")
			(effects
				(font
					(size 1.27 1.27)
				)
				(justify mirror)
			)
		)
		(duplicate_pad_numbers_are_jumpers no)
		(fp_line
			(start 1.524 -0.762)
			(end -1.524 -0.762)
			(stroke
				(width 0.1524)
				(type default)
			)
			(layer "B.SilkS")
		)
		(fp_line
			(start -1.524 -0.762)
			(end -1.524 0.762)
			(stroke
				(width 0.1524)
				(type default)
			)
			(layer "B.SilkS")
		)
		(fp_line
			(start 1.524 0.762)
			(end 1.524 -0.762)
			(stroke
				(width 0.1524)
				(type default)
			)
			(layer "B.SilkS")
		)
		(fp_line
			(start -1.524 0.762)
			(end 1.524 0.762)
			(stroke
				(width 0.1524)
				(type default)
			)
			(layer "B.SilkS")
		)
		(fp_line
			(start 1.1049 -0.724916)
			(end 1.1049 0.724916)
			(stroke
				(width 0.1)
				(type default)
			)
			(layer "B.Fab")
		)
		(fp_line
			(start -1.1049 -0.724916)
			(end 1.1049 -0.724916)
			(stroke
				(width 0.1)
				(type default)
			)
			(layer "B.Fab")
		)
		(fp_line
			(start 1.1049 0.724916)
			(end -1.1049 0.724916)
			(stroke
				(width 0.1)
				(type default)
			)
			(layer "B.Fab")
		)
		(fp_line
			(start -1.1049 0.724916)
			(end -1.1049 -0.724916)
			(stroke
				(width 0.1)
				(type default)
			)
			(layer "B.Fab")
		)
		(pad "1" smd rect
			(at 0.889 0 90)
			(size 1.016 1.27)
			(layers "B.Cu" "B.Mask" "B.Paste")
			(net "SW_P12V_AUX_PVDDCR_CPU1_P1_FLT")
		)
		(pad "2" smd rect
			(at -0.889 0 90)
			(size 1.016 1.27)
			(layers "B.Cu" "B.Mask" "B.Paste")
			(net "GND")
		)
	)
	(footprint ""
		(layer "B.Cu")
		(at 134.779766 -408.517344 90)
		(property "Reference" "C6738"
			(at 0 0 90)
			(layer "B.SilkS")
			(hide yes)
			(effects
				(font
					(size 1.27 1.27)
				)
				(justify mirror)
			)
		)
		(property "Value" ""
			(at 0 0 90)
			(layer "B.Fab")
			(effects
				(font
					(size 1.27 1.27)
				)
				(justify mirror)
			)
		)
		(duplicate_pad_numbers_are_jumpers no)
		(fp_line
			(start 0.299974 -0.150114)
			(end -0.299974 -0.150114)
			(stroke
				(width 0.1)
				(type default)
			)
			(layer "B.Fab")
		)
		(fp_line
			(start -0.299974 -0.150114)
			(end -0.299974 0.150114)
			(stroke
				(width 0.1)
				(type default)
			)
			(layer "B.Fab")
		)
		(fp_line
			(start 0.299974 0.150114)
			(end 0.299974 -0.150114)
			(stroke
				(width 0.1)
				(type default)
			)
			(layer "B.Fab")
		)
		(fp_line
			(start -0.299974 0.150114)
			(end 0.299974 0.150114)
			(stroke
				(width 0.1)
				(type default)
			)
			(layer "B.Fab")
		)
		(pad "1" smd rect
			(at 0.2667 0 270)
			(size 0.3048 0.381)
			(layers "B.Cu" "B.Mask" "B.Paste")
			(net "P5E_CPU1_P3_TX_BUF_C_DN<6>")
		)
		(pad "2" smd rect
			(at -0.2667 0 270)
			(size 0.3048 0.381)
			(layers "B.Cu" "B.Mask" "B.Paste")
			(net "P5E_CPU1_P3_TX_BUF_DN<6>")
		)
	)
	(footprint ""
		(layer "B.Cu")
		(at 277.192232 -192.660016)
		(property "Reference" "C151"
			(at 0 0 0)
			(layer "B.SilkS")
			(hide yes)
			(effects
				(font
					(size 1.27 1.27)
				)
				(justify mirror)
			)
		)
		(property "Value" ""
			(at 0 0 0)
			(layer "B.Fab")
			(effects
				(font
					(size 1.27 1.27)
				)
				(justify mirror)
			)
		)
		(duplicate_pad_numbers_are_jumpers no)
		(fp_line
			(start -1.524 -0.762)
			(end -1.524 0.762)
			(stroke
				(width 0.1524)
				(type default)
			)
			(layer "B.SilkS")
		)
		(fp_line
			(start -1.524 0.762)
			(end 1.524 0.762)
			(stroke
				(width 0.1524)
				(type default)
			)
			(layer "B.SilkS")
		)
		(fp_line
			(start 1.524 -0.762)
			(end -1.524 -0.762)
			(stroke
				(width 0.1524)
				(type default)
			)
			(layer "B.SilkS")
		)
		(fp_line
			(start 1.524 0.762)
			(end 1.524 -0.762)
			(stroke
				(width 0.1524)
				(type default)
			)
			(layer "B.SilkS")
		)
		(fp_line
			(start -1.1049 -0.724916)
			(end 1.1049 -0.724916)
			(stroke
				(width 0.1)
				(type default)
			)
			(layer "B.Fab")
		)
		(fp_line
			(start -1.1049 0.724916)
			(end -1.1049 -0.724916)
			(stroke
				(width 0.1)
				(type default)
			)
			(layer "B.Fab")
		)
		(fp_line
			(start 1.1049 -0.724916)
			(end 1.1049 0.724916)
			(stroke
				(width 0.1)
				(type default)
			)
			(layer "B.Fab")
		)
		(fp_line
			(start 1.1049 0.724916)
			(end -1.1049 0.724916)
			(stroke
				(width 0.1)
				(type default)
			)
			(layer "B.Fab")
		)
		(pad "1" smd rect
			(at 0.889 0)
			(size 1.016 1.27)
			(layers "B.Cu" "B.Mask" "B.Paste")
			(net "P12V_MEM_CPU0")
		)
		(pad "2" smd rect
			(at -0.889 0)
			(size 1.016 1.27)
			(layers "B.Cu" "B.Mask" "B.Paste")
			(net "GND")
		)
	)
	(footprint ""
		(layer "B.Cu")
		(at 230.886 -331.724 180)
		(property "Reference" "R6780"
			(at 0 0 0)
			(layer "B.SilkS")
			(hide yes)
			(effects
				(font
					(size 1.27 1.27)
				)
				(justify mirror)
			)
		)
		(property "Value" ""
			(at 0 0 0)
			(layer "B.Fab")
			(effects
				(font
					(size 1.27 1.27)
				)
				(justify mirror)
			)
		)
		(duplicate_pad_numbers_are_jumpers no)
		(fp_line
			(start 0.32512 0.175006)
			(end 0.32512 -0.175006)
			(stroke
				(width 0.1)
				(type default)
			)
			(layer "B.Fab")
		)
		(fp_line
			(start 0.32512 -0.175006)
			(end -0.32512 -0.175006)
			(stroke
				(width 0.1)
				(type default)
			)
			(layer "B.Fab")
		)
		(fp_line
			(start -0.32512 0.175006)
			(end 0.32512 0.175006)
			(stroke
				(width 0.1)
				(type default)
			)
			(layer "B.Fab")
		)
		(fp_line
			(start -0.32512 -0.175006)
			(end -0.32512 0.175006)
			(stroke
				(width 0.1)
				(type default)
			)
			(layer "B.Fab")
		)
		(pad "1" smd rect
			(at 0.2667 0)
			(size 0.3048 0.381)
			(layers "B.Cu" "B.Mask" "B.Paste")
			(net "SMB_MUX_RT_SCL")
		)
		(pad "2" smd rect
			(at -0.2667 0 180)
			(size 0.3048 0.381)
			(layers "B.Cu" "B.Mask" "B.Paste")
			(net "SMB_MUX_RT_R1_SCL")
		)
	)
	(footprint ""
		(layer "B.Cu")
		(at 89.122504 -408.517344 90)
		(property "Reference" "C6688"
			(at 0 0 90)
			(layer "B.SilkS")
			(hide yes)
			(effects
				(font
					(size 1.27 1.27)
				)
				(justify mirror)
			)
		)
		(property "Value" ""
			(at 0 0 90)
			(layer "B.Fab")
			(effects
				(font
					(size 1.27 1.27)
				)
				(justify mirror)
			)
		)
		(duplicate_pad_numbers_are_jumpers no)
		(fp_line
			(start 0.299974 -0.150114)
			(end -0.299974 -0.150114)
			(stroke
				(width 0.1)
				(type default)
			)
			(layer "B.Fab")
		)
		(fp_line
			(start -0.299974 -0.150114)
			(end -0.299974 0.150114)
			(stroke
				(width 0.1)
				(type default)
			)
			(layer "B.Fab")
		)
		(fp_line
			(start 0.299974 0.150114)
			(end 0.299974 -0.150114)
			(stroke
				(width 0.1)
				(type default)
			)
			(layer "B.Fab")
		)
		(fp_line
			(start -0.299974 0.150114)
			(end 0.299974 0.150114)
			(stroke
				(width 0.1)
				(type default)
			)
			(layer "B.Fab")
		)
		(pad "1" smd rect
			(at 0.2667 0 270)
			(size 0.3048 0.381)
			(layers "B.Cu" "B.Mask" "B.Paste")
			(net "P5E_CPU1_P1_TX_BUF_C_DN<13>")
		)
		(pad "2" smd rect
			(at -0.2667 0 270)
			(size 0.3048 0.381)
			(layers "B.Cu" "B.Mask" "B.Paste")
			(net "P5E_CPU1_P1_TX_BUF_DN<13>")
		)
	)
	(footprint ""
		(layer "B.Cu")
		(at 356.29596 -259.845048 180)
		(property "Reference" "C2131"
			(at 0 0 0)
			(layer "B.SilkS")
			(hide yes)
			(effects
				(font
					(size 1.27 1.27)
				)
				(justify mirror)
			)
		)
		(property "Value" ""
			(at 0 0 0)
			(layer "B.Fab")
			(effects
				(font
					(size 1.27 1.27)
				)
				(justify mirror)
			)
		)
		(duplicate_pad_numbers_are_jumpers no)
		(fp_line
			(start 0.7874 0.4064)
			(end 0.7874 -0.4064)
			(stroke
				(width 0.1524)
				(type default)
			)
			(layer "B.SilkS")
		)
		(fp_line
			(start 0.7874 -0.4064)
			(end -0.7874 -0.4064)
			(stroke
				(width 0.1524)
				(type default)
			)
			(layer "B.SilkS")
		)
		(fp_line
			(start -0.7874 0.4064)
			(end 0.7874 0.4064)
			(stroke
				(width 0.1524)
				(type default)
			)
			(layer "B.SilkS")
		)
		(fp_line
			(start -0.7874 -0.4064)
			(end -0.7874 0.4064)
			(stroke
				(width 0.1524)
				(type default)
			)
			(layer "B.SilkS")
		)
		(fp_line
			(start 0.67945 0.3048)
			(end 0.67945 -0.305054)
			(stroke
				(width 0.1)
				(type default)
			)
			(layer "B.Fab")
		)
		(fp_line
			(start 0.67945 -0.305054)
			(end 0.12065 -0.305054)
			(stroke
				(width 0.1)
				(type default)
			)
			(layer "B.Fab")
		)
		(fp_line
			(start 0.12065 0.3048)
			(end 0.67945 0.3048)
			(stroke
				(width 0.1)
				(type default)
			)
			(layer "B.Fab")
		)
		(fp_line
			(start 0.12065 0.2794)
			(end 0.12065 0.3048)
			(stroke
				(width 0.1)
				(type default)
			)
			(layer "B.Fab")
		)
		(fp_line
			(start 0.12065 -0.2794)
			(end -0.12065 -0.2794)
			(stroke
				(width 0.1)
				(type default)
			)
			(layer "B.Fab")
		)
		(fp_line
			(start 0.12065 -0.305054)
			(end 0.12065 -0.2794)
			(stroke
				(width 0.1)
				(type default)
			)
			(layer "B.Fab")
		)
		(fp_line
			(start -0.120396 0.3048)
			(end -0.120396 0.2794)
			(stroke
				(width 0.1)
				(type default)
			)
			(layer "B.Fab")
		)
		(fp_line
			(start -0.120396 0.2794)
			(end 0.12065 0.2794)
			(stroke
				(width 0.1)
				(type default)
			)
			(layer "B.Fab")
		)
		(fp_line
			(start -0.12065 -0.2794)
			(end -0.12065 -0.3048)
			(stroke
				(width 0.1)
				(type default)
			)
			(layer "B.Fab")
		)
		(fp_line
			(start -0.12065 -0.3048)
			(end -0.67945 -0.3048)
			(stroke
				(width 0.1)
				(type default)
			)
			(layer "B.Fab")
		)
		(fp_line
			(start -0.67945 0.3048)
			(end -0.120396 0.3048)
			(stroke
				(width 0.1)
				(type default)
			)
			(layer "B.Fab")
		)
		(fp_line
			(start -0.67945 -0.3048)
			(end -0.67945 0.3048)
			(stroke
				(width 0.1)
				(type default)
			)
			(layer "B.Fab")
		)
		(pad "1" smd circle
			(at 0.40005 0)
			(size 0 0)
			(layers "B.Cu" "B.Mask" "B.Paste")
			(net "PVDDIO_P0")
		)
		(pad "2" smd circle
			(at -0.40005 0)
			(size 0 0)
			(layers "B.Cu" "B.Mask" "B.Paste")
			(net "GND")
		)
	)
	(footprint ""
		(layer "B.Cu")
		(at 354.818696 -165.72992 90)
		(property "Reference" "PC571_5"
			(at 0 0 90)
			(layer "B.SilkS")
			(hide yes)
			(effects
				(font
					(size 1.27 1.27)
				)
				(justify mirror)
			)
		)
		(property "Value" ""
			(at 0 0 90)
			(layer "B.Fab")
			(effects
				(font
					(size 1.27 1.27)
				)
				(justify mirror)
			)
		)
		(duplicate_pad_numbers_are_jumpers no)
		(fp_line
			(start 1.524 -0.762)
			(end -1.524 -0.762)
			(stroke
				(width 0.1524)
				(type default)
			)
			(layer "B.SilkS")
		)
		(fp_line
			(start -1.524 -0.762)
			(end -1.524 0.762)
			(stroke
				(width 0.1524)
				(type default)
			)
			(layer "B.SilkS")
		)
		(fp_line
			(start 1.524 0.762)
			(end 1.524 -0.762)
			(stroke
				(width 0.1524)
				(type default)
			)
			(layer "B.SilkS")
		)
		(fp_line
			(start -1.524 0.762)
			(end 1.524 0.762)
			(stroke
				(width 0.1524)
				(type default)
			)
			(layer "B.SilkS")
		)
		(fp_line
			(start 1.1049 -0.724916)
			(end 1.1049 0.724916)
			(stroke
				(width 0.1)
				(type default)
			)
			(layer "B.Fab")
		)
		(fp_line
			(start -1.1049 -0.724916)
			(end 1.1049 -0.724916)
			(stroke
				(width 0.1)
				(type default)
			)
			(layer "B.Fab")
		)
		(fp_line
			(start 1.1049 0.724916)
			(end -1.1049 0.724916)
			(stroke
				(width 0.1)
				(type default)
			)
			(layer "B.Fab")
		)
		(fp_line
			(start -1.1049 0.724916)
			(end -1.1049 -0.724916)
			(stroke
				(width 0.1)
				(type default)
			)
			(layer "B.Fab")
		)
		(pad "1" smd rect
			(at 0.889 0 90)
			(size 1.016 1.27)
			(layers "B.Cu" "B.Mask" "B.Paste")
			(net "SW_P12V_AUX_PVDDCR_CPU0_P0_FLT")
		)
		(pad "2" smd rect
			(at -0.889 0 90)
			(size 1.016 1.27)
			(layers "B.Cu" "B.Mask" "B.Paste")
			(net "GND")
		)
	)
	(footprint ""
		(layer "B.Cu")
		(at 106.48823 -250.891294 180)
		(property "Reference" "C2327"
			(at 0 0 0)
			(layer "B.SilkS")
			(hide yes)
			(effects
				(font
					(size 1.27 1.27)
				)
				(justify mirror)
			)
		)
		(property "Value" ""
			(at 0 0 0)
			(layer "B.Fab")
			(effects
				(font
					(size 1.27 1.27)
				)
				(justify mirror)
			)
		)
		(duplicate_pad_numbers_are_jumpers no)
		(fp_line
			(start 0.7874 0.4064)
			(end 0.7874 -0.4064)
			(stroke
				(width 0.1524)
				(type default)
			)
			(layer "B.SilkS")
		)
		(fp_line
			(start 0.7874 -0.4064)
			(end -0.7874 -0.4064)
			(stroke
				(width 0.1524)
				(type default)
			)
			(layer "B.SilkS")
		)
		(fp_line
			(start -0.7874 0.4064)
			(end 0.7874 0.4064)
			(stroke
				(width 0.1524)
				(type default)
			)
			(layer "B.SilkS")
		)
		(fp_line
			(start -0.7874 -0.4064)
			(end -0.7874 0.4064)
			(stroke
				(width 0.1524)
				(type default)
			)
			(layer "B.SilkS")
		)
		(fp_line
			(start 0.67945 0.3048)
			(end 0.67945 -0.305054)
			(stroke
				(width 0.1)
				(type default)
			)
			(layer "B.Fab")
		)
		(fp_line
			(start 0.67945 -0.305054)
			(end 0.12065 -0.305054)
			(stroke
				(width 0.1)
				(type default)
			)
			(layer "B.Fab")
		)
		(fp_line
			(start 0.12065 0.3048)
			(end 0.67945 0.3048)
			(stroke
				(width 0.1)
				(type default)
			)
			(layer "B.Fab")
		)
		(fp_line
			(start 0.12065 0.2794)
			(end 0.12065 0.3048)
			(stroke
				(width 0.1)
				(type default)
			)
			(layer "B.Fab")
		)
		(fp_line
			(start 0.12065 -0.2794)
			(end -0.12065 -0.2794)
			(stroke
				(width 0.1)
				(type default)
			)
			(layer "B.Fab")
		)
		(fp_line
			(start 0.12065 -0.305054)
			(end 0.12065 -0.2794)
			(stroke
				(width 0.1)
				(type default)
			)
			(layer "B.Fab")
		)
		(fp_line
			(start -0.120396 0.3048)
			(end -0.120396 0.2794)
			(stroke
				(width 0.1)
				(type default)
			)
			(layer "B.Fab")
		)
		(fp_line
			(start -0.120396 0.2794)
			(end 0.12065 0.2794)
			(stroke
				(width 0.1)
				(type default)
			)
			(layer "B.Fab")
		)
		(fp_line
			(start -0.12065 -0.2794)
			(end -0.12065 -0.3048)
			(stroke
				(width 0.1)
				(type default)
			)
			(layer "B.Fab")
		)
		(fp_line
			(start -0.12065 -0.3048)
			(end -0.67945 -0.3048)
			(stroke
				(width 0.1)
				(type default)
			)
			(layer "B.Fab")
		)
		(fp_line
			(start -0.67945 0.3048)
			(end -0.120396 0.3048)
			(stroke
				(width 0.1)
				(type default)
			)
			(layer "B.Fab")
		)
		(fp_line
			(start -0.67945 -0.3048)
			(end -0.67945 0.3048)
			(stroke
				(width 0.1)
				(type default)
			)
			(layer "B.Fab")
		)
		(pad "1" smd circle
			(at 0.40005 0)
			(size 0 0)
			(layers "B.Cu" "B.Mask" "B.Paste")
			(net "PVDDCR_CPU0_P1")
		)
		(pad "2" smd circle
			(at -0.40005 0)
			(size 0 0)
			(layers "B.Cu" "B.Mask" "B.Paste")
			(net "GND")
		)
	)
	(footprint ""
		(layer "B.Cu")
		(at 113.451386 -246.447564 -60)
		(property "Reference" "C2342"
			(at 0 0 120)
			(layer "B.SilkS")
			(hide yes)
			(effects
				(font
					(size 1.27 1.27)
				)
				(justify mirror)
			)
		)
		(property "Value" ""
			(at 0 0 120)
			(layer "B.Fab")
			(effects
				(font
					(size 1.27 1.27)
				)
				(justify mirror)
			)
		)
		(duplicate_pad_numbers_are_jumpers no)
		(fp_line
			(start -0.787516 0.406438)
			(end 0.787425 0.40652)
			(stroke
				(width 0.1524)
				(type default)
			)
			(layer "B.SilkS")
		)
		(fp_line
			(start -0.787425 -0.40652)
			(end -0.787516 0.406438)
			(stroke
				(width 0.1524)
				(type default)
			)
			(layer "B.SilkS")
		)
		(fp_line
			(start 0.787425 0.40652)
			(end 0.787516 -0.406438)
			(stroke
				(width 0.1524)
				(type default)
			)
			(layer "B.SilkS")
		)
		(fp_line
			(start 0.787516 -0.406438)
			(end -0.787425 -0.40652)
			(stroke
				(width 0.1524)
				(type default)
			)
			(layer "B.SilkS")
		)
		(fp_line
			(start -0.679568 0.304811)
			(end -0.120258 0.304812)
			(stroke
				(width 0.1)
				(type default)
			)
			(layer "B.Fab")
		)
		(fp_line
			(start -0.120258 0.304812)
			(end -0.120334 0.279545)
			(stroke
				(width 0.1)
				(type default)
			)
			(layer "B.Fab")
		)
		(fp_line
			(start -0.120334 0.279545)
			(end 0.120587 0.279326)
			(stroke
				(width 0.1)
				(type default)
			)
			(layer "B.Fab")
		)
		(fp_line
			(start 0.120536 0.304813)
			(end 0.6795 0.304908)
			(stroke
				(width 0.1)
				(type default)
			)
			(layer "B.Fab")
		)
		(fp_line
			(start 0.120587 0.279326)
			(end 0.120536 0.304813)
			(stroke
				(width 0.1)
				(type default)
			)
			(layer "B.Fab")
		)
		(fp_line
			(start -0.6795 -0.304908)
			(end -0.679568 0.304811)
			(stroke
				(width 0.1)
				(type default)
			)
			(layer "B.Fab")
		)
		(fp_line
			(start 0.6795 0.304908)
			(end 0.679475 -0.305158)
			(stroke
				(width 0.1)
				(type default)
			)
			(layer "B.Fab")
		)
		(fp_line
			(start -0.120587 -0.279326)
			(end -0.120536 -0.304813)
			(stroke
				(width 0.1)
				(type default)
			)
			(layer "B.Fab")
		)
		(fp_line
			(start -0.120536 -0.304813)
			(end -0.6795 -0.304908)
			(stroke
				(width 0.1)
				(type default)
			)
			(layer "B.Fab")
		)
		(fp_line
			(start 0.120554 -0.279418)
			(end -0.120587 -0.279326)
			(stroke
				(width 0.1)
				(type default)
			)
			(layer "B.Fab")
		)
		(fp_line
			(start 0.120732 -0.305125)
			(end 0.120554 -0.279418)
			(stroke
				(width 0.1)
				(type default)
			)
			(layer "B.Fab")
		)
		(fp_line
			(start 0.679475 -0.305158)
			(end 0.120732 -0.305125)
			(stroke
				(width 0.1)
				(type default)
			)
			(layer "B.Fab")
		)
		(pad "1" smd circle
			(at 0.40005 0 120)
			(size 0 0)
			(layers "B.Cu" "B.Mask" "B.Paste")
			(net "PVDDCR_CPU0_P1")
		)
		(pad "2" smd circle
			(at -0.40005 0 120)
			(size 0 0)
			(layers "B.Cu" "B.Mask" "B.Paste")
			(net "GND")
		)
	)
)
